# T6G (Grand Teton) — schematic netlist excerpt (pin names and nets, part order shuffled) for the footprints in the layout excerpt that follows; sources: Cadence DE-HDL packaged netlist, KiCad conversion of 04192023_DAF0TMB3IC0_F0TG_MB_C_brd_V02_OCP.brd

Q104  MOSFET_NCH_DUAL  PJT138K IC  pkg SOT363XD  page 126
  S1  = GND
  G1  = GPU_FPGA_OVERT_N
  D2  = GPU_FPGA_OVERT_ISO_N
  S2  = GND
  G2  = GPU_FPGA_OVERT
  D1  = GPU_FPGA_OVERT

Q18  BSS138DW7F  BSS138DW-7-F IC  pkg SOT363A  page 259
  S1  = GND
  G1  = PWRGD_P12V_MEM_CPU0_EN
  D2  = PWRGD_P12V_MEM_CPU0
  S2  = GND
  G2  = PWRGD_P12V_MEM_CPU0_EN_N
  D1  = PWRGD_P12V_MEM_CPU0_EN_N

(kicad_pcb
	(version 20260206)
	(generator "pcbnew")
	(generator_version "10.0")
	(general
		(thickness 1.6)
		(legacy_teardrops no)
	)
	(paper "A4")
	(title_block
		(title "04192023_DAF0TMB3IC0_F0TG_MB_C_brd_V02_OCP.brd")
		(comment 1 "Grand Teton / footprints 3652-3653 of 8354")
	)
	(layers
		(0 "F.Cu" signal "TOP")
		(4 "In1.Cu" signal "GND")
		(6 "In2.Cu" signal "IN1")
		(8 "In3.Cu" signal "GND1")
		(10 "In4.Cu" signal "IN2")
		(12 "In5.Cu" signal "GND2")
		(14 "In6.Cu" signal "IN3")
		(16 "In7.Cu" signal "GND3")
		(18 "In8.Cu" signal "VCC")
		(20 "In9.Cu" signal "VCC1")
		(22 "In10.Cu" signal "GND4")
		(24 "In11.Cu" signal "IN4")
		(26 "In12.Cu" signal "GND5")
		(28 "In13.Cu" signal "IN5")
		(30 "In14.Cu" signal "GND6")
		(32 "In15.Cu" signal "IN6")
		(34 "In16.Cu" signal "GND7")
		(2 "B.Cu" signal "BOTTOM")
		(9 "F.Adhes" user "F.Adhesive")
		(11 "B.Adhes" user "B.Adhesive")
		(13 "F.Paste" user "Package Geometry/Pastemask Top")
		(15 "B.Paste" user "Package Geometry/Pastemask Bottom")
		(5 "F.SilkS" user "Ref Des/Silkscreen Top")
		(7 "B.SilkS" user "Ref Des/Silkscreen Bottom")
		(1 "F.Mask" user "Board Geometry/Soldermask Top")
		(3 "B.Mask" user "Board Geometry/Soldermask Bottom")
		(17 "Dwgs.User" user "User.Drawings")
		(19 "Cmts.User" user "User.Comments")
		(21 "Eco1.User" user "User.Eco1")
		(23 "Eco2.User" user "User.Eco2")
		(25 "Edge.Cuts" user "Board Geometry/Outline")
		(27 "Margin" user)
		(31 "F.CrtYd" user "Package Geometry/Place Bound Top")
		(29 "B.CrtYd" user "Package Geometry/Place Bound Bottom")
		(35 "F.Fab" user "Ref Des/Assembly Top")
		(33 "B.Fab" user "Ref Des/Assembly Bottom")
	)
	(footprint ""
		(layer "F.Cu")
		(at 304.293778 -434.264308 180)
		(property "Reference" "Q104"
			(at 4.643374 -1.833372 0)
			(unlocked yes)
			(layer "F.SilkS")
			(effects
				(font
					(size 0.7874 0.5842)
					(thickness 0.1524)
				)
				(justify left)
			)
		)
		(property "Value" ""
			(at 0 0 180)
			(layer "F.Fab")
			(effects
				(font
					(size 1.27 1.27)
				)
			)
		)
		(duplicate_pad_numbers_are_jumpers no)
		(fp_line
			(start 1.332738 1.100074)
			(end -1.332738 1.100074)
			(stroke
				(width 0.1524)
				(type default)
			)
			(layer "F.SilkS")
		)
		(fp_line
			(start 1.332738 -1.100074)
			(end 1.332738 1.100074)
			(stroke
				(width 0.1524)
				(type default)
			)
			(layer "F.SilkS")
		)
		(fp_line
			(start 0.4826 -1.100074)
			(end 1.332738 -1.100074)
			(stroke
				(width 0.1524)
				(type default)
			)
			(layer "F.SilkS")
		)
		(fp_line
			(start 0 -0.541274)
			(end 0.4826 -1.100074)
			(stroke
				(width 0.1524)
				(type default)
			)
			(layer "F.SilkS")
		)
		(fp_line
			(start -0.4826 -1.100074)
			(end 0 -0.541274)
			(stroke
				(width 0.1524)
				(type default)
			)
			(layer "F.SilkS")
		)
		(fp_line
			(start -1.332738 1.100074)
			(end -1.332738 -1.100074)
			(stroke
				(width 0.1524)
				(type default)
			)
			(layer "F.SilkS")
		)
		(fp_line
			(start -1.332738 -1.100074)
			(end -0.4826 -1.100074)
			(stroke
				(width 0.1524)
				(type default)
			)
			(layer "F.SilkS")
		)
		(fp_poly
			(pts
				(xy -1.489456 -1.189482) (xy -2.23393 -1.43764) (xy -1.737614 -1.933956)
			)
			(stroke
				(width 0)
				(type default)
			)
			(fill yes)
			(layer "F.SilkS")
		)
		(fp_line
			(start 0.674878 1.100074)
			(end -0.674878 1.100074)
			(stroke
				(width 0.1)
				(type default)
			)
			(layer "F.Fab")
		)
		(fp_line
			(start 0.674878 -1.100074)
			(end 0.674878 1.100074)
			(stroke
				(width 0.1)
				(type default)
			)
			(layer "F.Fab")
		)
		(fp_line
			(start -0.674878 1.100074)
			(end -0.674878 -1.100074)
			(stroke
				(width 0.1)
				(type default)
			)
			(layer "F.Fab")
		)
		(fp_line
			(start -0.674878 -1.100074)
			(end 0.674878 -1.100074)
			(stroke
				(width 0.1)
				(type default)
			)
			(layer "F.Fab")
		)
		(fp_poly
			(pts
				(xy -2.2352 -0.298958) (xy -2.2352 -1.001014) (xy -1.533144 -0.649986)
			)
			(stroke
				(width 0)
				(type default)
			)
			(fill yes)
			(layer "F.Fab")
		)
		(pad "1" smd rect
			(at -0.94996 -0.649986 270)
			(size 0.4318 0.508)
			(layers "F.Cu" "F.Mask" "F.Paste")
			(net "GND")
		)
		(pad "2" smd rect
			(at -0.94996 0 270)
			(size 0.4318 0.508)
			(layers "F.Cu" "F.Mask" "F.Paste")
			(net "GPU_FPGA_OVERT_N")
		)
		(pad "3" smd rect
			(at -0.94996 0.649986 270)
			(size 0.4318 0.508)
			(layers "F.Cu" "F.Mask" "F.Paste")
			(net "GPU_FPGA_OVERT_ISO_N")
		)
		(pad "4" smd rect
			(at 0.94996 0.649986 270)
			(size 0.4318 0.508)
			(layers "F.Cu" "F.Mask" "F.Paste")
			(net "GND")
		)
		(pad "5" smd rect
			(at 0.94996 0 270)
			(size 0.4318 0.508)
			(layers "F.Cu" "F.Mask" "F.Paste")
			(net "GPU_FPGA_OVERT")
		)
		(pad "6" smd rect
			(at 0.94996 -0.649986 270)
			(size 0.4318 0.508)
			(layers "F.Cu" "F.Mask" "F.Paste")
			(net "GPU_FPGA_OVERT")
		)
	)
	(footprint ""
		(layer "F.Cu")
		(at 102.154736 -123.64339 -90)
		(property "Reference" "Q18"
			(at -0.190754 1.882394 90)
			(unlocked yes)
			(layer "F.SilkS")
			(effects
				(font
					(size 0.7874 0.5842)
					(thickness 0.1524)
				)
			)
		)
		(property "Value" ""
			(at 0 0 270)
			(layer "F.Fab")
			(effects
				(font
					(size 1.27 1.27)
				)
			)
		)
		(duplicate_pad_numbers_are_jumpers no)
		(fp_line
			(start -1.7018 1.100074)
			(end -1.7018 -1.100074)
			(stroke
				(width 0.1524)
				(type default)
			)
			(layer "F.SilkS")
		)
		(fp_line
			(start 1.7018 1.100074)
			(end -1.7018 1.100074)
			(stroke
				(width 0.1524)
				(type default)
			)
			(layer "F.SilkS")
		)
		(fp_line
			(start -1.7018 -1.100074)
			(end 1.7018 -1.100074)
			(stroke
				(width 0.1524)
				(type default)
			)
			(layer "F.SilkS")
		)
		(fp_line
			(start 1.7018 -1.100074)
			(end 1.7018 1.100074)
			(stroke
				(width 0.1524)
				(type default)
			)
			(layer "F.SilkS")
		)
		(fp_poly
			(pts
				(xy -2.339594 -0.650748) (xy -2.893314 -0.354076) (xy -2.893314 -0.978916)
			)
			(stroke
				(width 0)
				(type default)
			)
			(fill yes)
			(layer "F.SilkS")
		)
		(fp_line
			(start -0.670052 1.100074)
			(end -0.670052 0.8001)
			(stroke
				(width 0.1)
				(type default)
			)
			(layer "F.Fab")
		)
		(fp_line
			(start 0.670052 1.100074)
			(end -0.670052 1.100074)
			(stroke
				(width 0.1)
				(type default)
			)
			(layer "F.Fab")
		)
		(fp_line
			(start -1.100074 0.8001)
			(end -1.100074 -0.8001)
			(stroke
				(width 0.1)
				(type default)
			)
			(layer "F.Fab")
		)
		(fp_line
			(start -0.670052 0.8001)
			(end -1.100074 0.8001)
			(stroke
				(width 0.1)
				(type default)
			)
			(layer "F.Fab")
		)
		(fp_line
			(start -0.670052 0.8001)
			(end -0.670052 -0.8001)
			(stroke
				(width 0.1)
				(type default)
			)
			(layer "F.Fab")
		)
		(fp_line
			(start 0.670052 0.8001)
			(end 0.670052 1.100074)
			(stroke
				(width 0.1)
				(type default)
			)
			(layer "F.Fab")
		)
		(fp_line
			(start 1.100074 0.8001)
			(end 0.670052 0.8001)
			(stroke
				(width 0.1)
				(type default)
			)
			(layer "F.Fab")
		)
		(fp_line
			(start -1.100074 -0.8001)
			(end -0.670052 -0.8001)
			(stroke
				(width 0.1)
				(type default)
			)
			(layer "F.Fab")
		)
		(fp_line
			(start -0.670052 -0.8001)
			(end -0.670052 -1.100074)
			(stroke
				(width 0.1)
				(type default)
			)
			(layer "F.Fab")
		)
		(fp_line
			(start 0.670052 -0.8001)
			(end 0.670052 0.8001)
			(stroke
				(width 0.1)
				(type default)
			)
			(layer "F.Fab")
		)
		(fp_line
			(start 0.670052 -0.8001)
			(end 1.100074 -0.8001)
			(stroke
				(width 0.1)
				(type default)
			)
			(layer "F.Fab")
		)
		(fp_line
			(start 1.100074 -0.8001)
			(end 1.100074 0.8001)
			(stroke
				(width 0.1)
				(type default)
			)
			(layer "F.Fab")
		)
		(fp_line
			(start -0.670052 -1.100074)
			(end 0.670052 -1.100074)
			(stroke
				(width 0.1)
				(type default)
			)
			(layer "F.Fab")
		)
		(fp_line
			(start 0.670052 -1.100074)
			(end 0.670052 -0.8001)
			(stroke
				(width 0.1)
				(type default)
			)
			(layer "F.Fab")
		)
		(fp_poly
			(pts
				(xy -2.33172 -0.338328) (xy -2.33172 -0.963168) (xy -1.778 -0.635)
			)
			(stroke
				(width 0)
				(type default)
			)
			(fill yes)
			(layer "F.Fab")
		)
		(pad "1" smd rect
			(at -0.937514 -0.649986)
			(size 0.3048 1.2446)
			(layers "F.Cu" "F.Mask" "F.Paste")
			(net "GND")
		)
		(pad "2" smd rect
			(at -0.937514 0)
			(size 0.3048 1.2446)
			(layers "F.Cu" "F.Mask" "F.Paste")
			(net "PWRGD_P12V_MEM_CPU0_EN")
		)
		(pad "3" smd rect
			(at -0.937514 0.649986)
			(size 0.3048 1.2446)
			(layers "F.Cu" "F.Mask" "F.Paste")
			(net "PWRGD_P12V_MEM_CPU0")
		)
		(pad "4" smd rect
			(at 0.937514 0.649986)
			(size 0.3048 1.2446)
			(layers "F.Cu" "F.Mask" "F.Paste")
			(net "GND")
		)
		(pad "5" smd rect
			(at 0.937514 0)
			(size 0.3048 1.2446)
			(layers "F.Cu" "F.Mask" "F.Paste")
			(net "PWRGD_P12V_MEM_CPU0_EN_N")
		)
		(pad "6" smd rect
			(at 0.937514 -0.649986)
			(size 0.3048 1.2446)
			(layers "F.Cu" "F.Mask" "F.Paste")
			(net "PWRGD_P12V_MEM_CPU0_EN_N")
		)
	)
)
